(kicad_pcb
	(version 20260206)
	(generator "pcbnew")
	(generator_version "10.0")
	(general
		(thickness 1.6)
		(legacy_teardrops no)
	)
	(paper "A4")
	(title_block
		(title "03242023_DA0F0TMBIJ0_F0T_Motherboard_J_brd_V01_OCP.brd")
		(comment 1 "Grand Teton / footprint 2591 of 6105 (J108), pads 1-48 of 48")
	)
	(layers
		(0 "F.Cu" signal "TOP")
		(4 "In1.Cu" signal "GND")
		(6 "In2.Cu" signal "IN1")
		(8 "In3.Cu" signal "GND1")
		(10 "In4.Cu" signal "IN2")
		(12 "In5.Cu" signal "GND2")
		(14 "In6.Cu" signal "IN3")
		(16 "In7.Cu" signal "GND3")
		(18 "In8.Cu" signal "VCC")
		(20 "In9.Cu" signal "VCC1")
		(22 "In10.Cu" signal "GND4")
		(24 "In11.Cu" signal "IN4")
		(26 "In12.Cu" signal "GND5")
		(28 "In13.Cu" signal "IN5")
		(30 "In14.Cu" signal "GND6")
		(32 "In15.Cu" signal "IN6")
		(34 "In16.Cu" signal "GND7")
		(2 "B.Cu" signal "BOTTOM")
		(9 "F.Adhes" user "F.Adhesive")
		(11 "B.Adhes" user "B.Adhesive")
		(13 "F.Paste" user "Package Geometry/Pastemask Top")
		(15 "B.Paste" user "Package Geometry/Pastemask Bottom")
		(5 "F.SilkS" user "Ref Des/Silkscreen Top")
		(7 "B.SilkS" user "Ref Des/Silkscreen Bottom")
		(1 "F.Mask" user "Board Geometry/Soldermask Top")
		(3 "B.Mask" user "Board Geometry/Soldermask Bottom")
		(17 "Dwgs.User" user "User.Drawings")
		(19 "Cmts.User" user "User.Comments")
		(21 "Eco1.User" user "User.Eco1")
		(23 "Eco2.User" user "User.Eco2")
		(25 "Edge.Cuts" user "Board Geometry/Outline")
		(27 "Margin" user)
		(31 "F.CrtYd" user "Package Geometry/Place Bound Top")
		(29 "B.CrtYd" user "Package Geometry/Place Bound Bottom")
		(35 "F.Fab" user "Ref Des/Assembly Top")
		(33 "B.Fab" user "Ref Des/Assembly Bottom")
	)
	(footprint ""
		(layer "F.Cu")
		(at 314.65012 -440.489848)
		(property "Reference" "J108"
			(at 12.6238 23.28799 0)
			(unlocked yes)
			(layer "F.SilkS")
			(effects
				(font
					(size 0.7874 0.5842)
					(thickness 0.1524)
				)
				(justify left)
			)
		)
		(property "Value" ""
			(at 0 0 0)
			(layer "F.Fab")
			(effects
				(font
					(size 1.27 1.27)
				)
			)
		)
		(duplicate_pad_numbers_are_jumpers no)
		(pad "A1" thru_hole rect
			(at 0 0 180)
			(size 0.766318 0.766318)
			(drill 0.359918)
			(layers "*.Cu" "*.Mask")
			(remove_unused_layers no)
			(net "GPU_3V3IO_RSVD3_FFU")
			(clearance 0.0508)
			(thermal_gap 0.0508)
			(padstack
				(mode front_inner_back)
				(layer "Inner"
					(shape circle)
					(size 0.766318 0.766318)
					(clearance 0.0508)
				)
				(layer "B.Cu"
					(shape rect)
					(size 0.766318 0.766318)
					(clearance 0.0508)
				)
			)
		)
		(pad "A2" thru_hole circle
			(at 1.999996 0.199898 180)
			(size 0.906272 0.906272)
			(drill 0.499872)
			(layers "*.Cu" "*.Mask")
			(remove_unused_layers no)
			(net "GND")
			(clearance 0.0508)
			(thermal_gap 0.0508)
		)
		(pad "A3" thru_hole circle
			(at 3.999992 0 180)
			(size 0.766318 0.766318)
			(drill 0.359918)
			(layers "*.Cu" "*.Mask")
			(remove_unused_layers no)
			(net "PRSNT_CABLE_GPU_A2_N")
			(clearance 0.0508)
			(thermal_gap 0.0508)
		)
		(pad "A4" thru_hole circle
			(at 5.999988 0.199898 180)
			(size 0.906272 0.906272)
			(drill 0.499872)
			(layers "*.Cu" "*.Mask")
			(remove_unused_layers no)
			(net "GND")
			(clearance 0.0508)
			(thermal_gap 0.0508)
		)
		(pad "A5" thru_hole circle
			(at 7.999984 0 180)
			(size 0.766318 0.766318)
			(drill 0.359918)
			(layers "*.Cu" "*.Mask")
			(remove_unused_layers no)
			(net "GPU_3V3IO_RSVD5_FFU")
			(clearance 0.0508)
			(thermal_gap 0.0508)
		)
		(pad "A6" thru_hole circle
			(at 9.99998 0.199898 180)
			(size 0.906272 0.906272)
			(drill 0.499872)
			(layers "*.Cu" "*.Mask")
			(remove_unused_layers no)
			(net "GND")
			(clearance 0.0508)
			(thermal_gap 0.0508)
		)
		(pad "A7" thru_hole circle
			(at 11.999976 0 180)
			(size 0.766318 0.766318)
			(drill 0.359918)
			(layers "*.Cu" "*.Mask")
			(remove_unused_layers no)
			(net "GPU_FPGA_OVERT_N")
			(clearance 0.0508)
			(thermal_gap 0.0508)
		)
		(pad "A8" thru_hole circle
			(at 13.999972 0.199898 180)
			(size 0.906272 0.906272)
			(drill 0.499872)
			(layers "*.Cu" "*.Mask")
			(remove_unused_layers no)
			(net "GND")
			(clearance 0.0508)
			(thermal_gap 0.0508)
		)
		(pad "B1" thru_hole circle
			(at 0 1.199896 180)
			(size 0.906272 0.906272)
			(drill 0.499872)
			(layers "*.Cu" "*.Mask")
			(remove_unused_layers no)
			(net "GND")
			(clearance 0.0508)
			(thermal_gap 0.0508)
		)
		(pad "B3" thru_hole circle
			(at 3.999992 1.199896 180)
			(size 0.906272 0.906272)
			(drill 0.499872)
			(layers "*.Cu" "*.Mask")
			(remove_unused_layers no)
			(net "GND")
			(clearance 0.0508)
			(thermal_gap 0.0508)
		)
		(pad "B5" thru_hole circle
			(at 7.999984 1.199896 180)
			(size 0.906272 0.906272)
			(drill 0.499872)
			(layers "*.Cu" "*.Mask")
			(remove_unused_layers no)
			(net "GND")
			(clearance 0.0508)
			(thermal_gap 0.0508)
		)
		(pad "B7" thru_hole circle
			(at 11.999976 1.199896 180)
			(size 0.906272 0.906272)
			(drill 0.499872)
			(layers "*.Cu" "*.Mask")
			(remove_unused_layers no)
			(net "GND")
			(clearance 0.0508)
			(thermal_gap 0.0508)
		)
		(pad "D2" thru_hole circle
			(at 1.999996 3.800094 180)
			(size 0.906272 0.906272)
			(drill 0.499872)
			(layers "*.Cu" "*.Mask")
			(remove_unused_layers no)
			(net "GND")
			(clearance 0.0508)
			(thermal_gap 0.0508)
		)
		(pad "D4" thru_hole circle
			(at 5.999988 3.800094 180)
			(size 0.906272 0.906272)
			(drill 0.499872)
			(layers "*.Cu" "*.Mask")
			(remove_unused_layers no)
			(net "GND")
			(clearance 0.0508)
			(thermal_gap 0.0508)
		)
		(pad "D6" thru_hole circle
			(at 9.99998 3.800094 180)
			(size 0.906272 0.906272)
			(drill 0.499872)
			(layers "*.Cu" "*.Mask")
			(remove_unused_layers no)
			(net "GND")
			(clearance 0.0508)
			(thermal_gap 0.0508)
		)
		(pad "D8" thru_hole circle
			(at 13.999972 3.800094 180)
			(size 0.906272 0.906272)
			(drill 0.499872)
			(layers "*.Cu" "*.Mask")
			(remove_unused_layers no)
			(net "GND")
			(clearance 0.0508)
			(thermal_gap 0.0508)
		)
		(pad "E1" thru_hole circle
			(at 0 4.800092 180)
			(size 0.906272 0.906272)
			(drill 0.499872)
			(layers "*.Cu" "*.Mask")
			(remove_unused_layers no)
			(net "GND")
			(clearance 0.0508)
			(thermal_gap 0.0508)
		)
		(pad "E3" thru_hole circle
			(at 3.999992 4.800092 180)
			(size 0.906272 0.906272)
			(drill 0.499872)
			(layers "*.Cu" "*.Mask")
			(remove_unused_layers no)
			(net "GND")
			(clearance 0.0508)
			(thermal_gap 0.0508)
		)
		(pad "E5" thru_hole circle
			(at 7.999984 4.800092 180)
			(size 0.906272 0.906272)
			(drill 0.499872)
			(layers "*.Cu" "*.Mask")
			(remove_unused_layers no)
			(net "GND")
			(clearance 0.0508)
			(thermal_gap 0.0508)
		)
		(pad "E7" thru_hole circle
			(at 11.999976 4.800092 180)
			(size 0.906272 0.906272)
			(drill 0.499872)
			(layers "*.Cu" "*.Mask")
			(remove_unused_layers no)
			(net "GND")
			(clearance 0.0508)
			(thermal_gap 0.0508)
		)
		(pad "G2" thru_hole circle
			(at 1.999996 7.400036 180)
			(size 0.906272 0.906272)
			(drill 0.499872)
			(layers "*.Cu" "*.Mask")
			(remove_unused_layers no)
			(net "GND")
			(clearance 0.0508)
			(thermal_gap 0.0508)
		)
		(pad "G4" thru_hole circle
			(at 5.999988 7.400036 180)
			(size 0.906272 0.906272)
			(drill 0.499872)
			(layers "*.Cu" "*.Mask")
			(remove_unused_layers no)
			(net "GND")
			(clearance 0.0508)
			(thermal_gap 0.0508)
		)
		(pad "G6" thru_hole circle
			(at 9.99998 7.400036 180)
			(size 0.906272 0.906272)
			(drill 0.499872)
			(layers "*.Cu" "*.Mask")
			(remove_unused_layers no)
			(net "GND")
			(clearance 0.0508)
			(thermal_gap 0.0508)
		)
		(pad "G8" thru_hole circle
			(at 13.999972 7.400036 180)
			(size 0.906272 0.906272)
			(drill 0.499872)
			(layers "*.Cu" "*.Mask")
			(remove_unused_layers no)
			(net "GND")
			(clearance 0.0508)
			(thermal_gap 0.0508)
		)
		(pad "H1" thru_hole circle
			(at 0 8.400034 180)
			(size 0.906272 0.906272)
			(drill 0.499872)
			(layers "*.Cu" "*.Mask")
			(remove_unused_layers no)
			(net "GND")
			(clearance 0.0508)
			(thermal_gap 0.0508)
		)
		(pad "H3" thru_hole circle
			(at 3.999992 8.400034 180)
			(size 0.906272 0.906272)
			(drill 0.499872)
			(layers "*.Cu" "*.Mask")
			(remove_unused_layers no)
			(net "GND")
			(clearance 0.0508)
			(thermal_gap 0.0508)
		)
		(pad "H5" thru_hole circle
			(at 7.999984 8.400034 180)
			(size 0.906272 0.906272)
			(drill 0.499872)
			(layers "*.Cu" "*.Mask")
			(remove_unused_layers no)
			(net "GND")
			(clearance 0.0508)
			(thermal_gap 0.0508)
		)
		(pad "H7" thru_hole circle
			(at 11.999976 8.400034 180)
			(size 0.906272 0.906272)
			(drill 0.499872)
			(layers "*.Cu" "*.Mask")
			(remove_unused_layers no)
			(net "GND")
			(clearance 0.0508)
			(thermal_gap 0.0508)
		)
		(pad "J2" thru_hole circle
			(at 1.999996 10.999978 180)
			(size 0.906272 0.906272)
			(drill 0.499872)
			(layers "*.Cu" "*.Mask")
			(remove_unused_layers no)
			(net "GND")
			(clearance 0.0508)
			(thermal_gap 0.0508)
		)
		(pad "J4" thru_hole circle
			(at 5.999988 10.999978 180)
			(size 0.906272 0.906272)
			(drill 0.499872)
			(layers "*.Cu" "*.Mask")
			(remove_unused_layers no)
			(net "GND")
			(clearance 0.0508)
			(thermal_gap 0.0508)
		)
		(pad "J6" thru_hole circle
			(at 9.99998 10.999978 180)
			(size 0.906272 0.906272)
			(drill 0.499872)
			(layers "*.Cu" "*.Mask")
			(remove_unused_layers no)
			(net "GND")
			(clearance 0.0508)
			(thermal_gap 0.0508)
		)
		(pad "J8" thru_hole circle
			(at 13.999972 10.999978 180)
			(size 0.906272 0.906272)
			(drill 0.499872)
			(layers "*.Cu" "*.Mask")
			(remove_unused_layers no)
			(net "GND")
			(clearance 0.0508)
			(thermal_gap 0.0508)
		)
		(pad "K1" thru_hole circle
			(at 0 11.999976 180)
			(size 0.906272 0.906272)
			(drill 0.499872)
			(layers "*.Cu" "*.Mask")
			(remove_unused_layers no)
			(net "GND")
			(clearance 0.0508)
			(thermal_gap 0.0508)
		)
		(pad "K3" thru_hole circle
			(at 3.999992 11.999976 180)
			(size 0.906272 0.906272)
			(drill 0.499872)
			(layers "*.Cu" "*.Mask")
			(remove_unused_layers no)
			(net "GND")
			(clearance 0.0508)
			(thermal_gap 0.0508)
		)
		(pad "K5" thru_hole circle
			(at 7.999984 11.999976 180)
			(size 0.906272 0.906272)
			(drill 0.499872)
			(layers "*.Cu" "*.Mask")
			(remove_unused_layers no)
			(net "GND")
			(clearance 0.0508)
			(thermal_gap 0.0508)
		)
		(pad "K7" thru_hole circle
			(at 11.999976 11.999976 180)
			(size 0.906272 0.906272)
			(drill 0.499872)
			(layers "*.Cu" "*.Mask")
			(remove_unused_layers no)
			(net "GND")
			(clearance 0.0508)
			(thermal_gap 0.0508)
		)
		(pad "M2" thru_hole circle
			(at 1.999996 14.59992 180)
			(size 0.906272 0.906272)
			(drill 0.499872)
			(layers "*.Cu" "*.Mask")
			(remove_unused_layers no)
			(net "GND")
			(clearance 0.0508)
			(thermal_gap 0.0508)
		)
		(pad "M4" thru_hole circle
			(at 5.999988 14.59992 180)
			(size 0.906272 0.906272)
			(drill 0.499872)
			(layers "*.Cu" "*.Mask")
			(remove_unused_layers no)
			(net "GND")
			(clearance 0.0508)
			(thermal_gap 0.0508)
		)
		(pad "M6" thru_hole circle
			(at 9.99998 14.59992 180)
			(size 0.906272 0.906272)
			(drill 0.499872)
			(layers "*.Cu" "*.Mask")
			(remove_unused_layers no)
			(net "GND")
			(clearance 0.0508)
			(thermal_gap 0.0508)
		)
		(pad "M8" thru_hole circle
			(at 13.999972 14.59992 180)
			(size 0.906272 0.906272)
			(drill 0.499872)
			(layers "*.Cu" "*.Mask")
			(remove_unused_layers no)
			(net "GND")
			(clearance 0.0508)
			(thermal_gap 0.0508)
		)
		(pad "N1" thru_hole circle
			(at 0 15.599918 180)
			(size 0.906272 0.906272)
			(drill 0.499872)
			(layers "*.Cu" "*.Mask")
			(remove_unused_layers no)
			(net "GND")
			(clearance 0.0508)
			(thermal_gap 0.0508)
		)
		(pad "N2" thru_hole circle
			(at 1.999996 15.80007 180)
			(size 0.766318 0.766318)
			(drill 0.359918)
			(layers "*.Cu" "*.Mask")
			(remove_unused_layers no)
			(net "NC_J108_N2")
			(clearance 0.0508)
			(thermal_gap 0.0508)
		)
		(pad "N3" thru_hole circle
			(at 3.999992 15.599918 180)
			(size 0.906272 0.906272)
			(drill 0.499872)
			(layers "*.Cu" "*.Mask")
			(remove_unused_layers no)
			(net "GND")
			(clearance 0.0508)
			(thermal_gap 0.0508)
		)
		(pad "N4" thru_hole circle
			(at 5.999988 15.80007 180)
			(size 0.766318 0.766318)
			(drill 0.359918)
			(layers "*.Cu" "*.Mask")
			(remove_unused_layers no)
			(net "NC_J108_N4")
			(clearance 0.0508)
			(thermal_gap 0.0508)
		)
		(pad "N5" thru_hole circle
			(at 7.999984 15.599918 180)
			(size 0.906272 0.906272)
			(drill 0.499872)
			(layers "*.Cu" "*.Mask")
			(remove_unused_layers no)
			(net "GND")
			(clearance 0.0508)
			(thermal_gap 0.0508)
		)
		(pad "N6" thru_hole circle
			(at 9.99998 15.80007 180)
			(size 0.766318 0.766318)
			(drill 0.359918)
			(layers "*.Cu" "*.Mask")
			(remove_unused_layers no)
			(net "NC_J108_N6")
			(clearance 0.0508)
			(thermal_gap 0.0508)
		)
		(pad "N7" thru_hole circle
			(at 11.999976 15.599918 180)
			(size 0.906272 0.906272)
			(drill 0.499872)
			(layers "*.Cu" "*.Mask")
			(remove_unused_layers no)
			(net "GND")
			(clearance 0.0508)
			(thermal_gap 0.0508)
		)
		(pad "N8" thru_hole circle
			(at 13.999972 15.80007 180)
			(size 0.766318 0.766318)
			(drill 0.359918)
			(layers "*.Cu" "*.Mask")
			(remove_unused_layers no)
			(net "PRSNT_CABLE_GPU_A3_N")
			(clearance 0.0508)
			(thermal_gap 0.0508)
		)
	)
)
